# BASEBOARD_FAB2 (Tioga Pass) — schematic netlist excerpt (pin names and nets, part order shuffled) for the footprints in the layout excerpt that follows; sources: Cadence DE-HDL packaged netlist, KiCad conversion of Wiwynn_Tioga_Pass_MB.brd

C4D44  CAP  220PF 50V 10% X7R  pkg 0402LF  page 213 : A = VR_PVCCIO_CPU1_AVSP ; B = VSENSE_PVCCIO_CPU1_AVSN
R6W30  RES  100.0K 1% CHIP  pkg 0603  page 176 : A = P3V3_STBY ; B = SPA_MID_DBG2_RX_BUF
C7B24  CAP_A  22.0UF 4V 20% X6S  pkg 0603V  page 131 : A = P1V05_PCH_STBY ; B = GND

(kicad_pcb
	(version 20260206)
	(generator "pcbnew")
	(generator_version "10.0")
	(general
		(thickness 1.6)
		(legacy_teardrops no)
	)
	(paper "A4")
	(title_block
		(title "Wiwynn_Tioga_Pass_MB.brd")
		(comment 1 "Tioga Pass / footprints 950-952 of 4770")
	)
	(layers
		(0 "F.Cu" signal "TOP")
		(4 "In1.Cu" signal "L2GND")
		(6 "In2.Cu" signal "L3")
		(8 "In3.Cu" signal "L4GND")
		(10 "In4.Cu" signal "L5")
		(12 "In5.Cu" signal "L6GND")
		(14 "In6.Cu" signal "L7VCC")
		(16 "In7.Cu" signal "L8VCC")
		(18 "In8.Cu" signal "L9GND")
		(20 "In9.Cu" signal "L10")
		(22 "In10.Cu" signal "L11GND")
		(24 "In11.Cu" signal "L12")
		(26 "In12.Cu" signal "L13GND")
		(2 "B.Cu" signal "BOTTOM")
		(9 "F.Adhes" user "F.Adhesive")
		(11 "B.Adhes" user "B.Adhesive")
		(13 "F.Paste" user "Package Geometry/Pastemask Top")
		(15 "B.Paste" user "Package Geometry/Pastemask Bottom")
		(5 "F.SilkS" user "Ref Des/Silkscreen Top")
		(7 "B.SilkS" user "Ref Des/Silkscreen Bottom")
		(1 "F.Mask" user "Board Geometry/Soldermask Top")
		(3 "B.Mask" user "Board Geometry/Soldermask Bottom")
		(17 "Dwgs.User" user "User.Drawings")
		(19 "Cmts.User" user "User.Comments")
		(21 "Eco1.User" user "User.Eco1")
		(23 "Eco2.User" user "User.Eco2")
		(25 "Edge.Cuts" user "Board Geometry/Outline")
		(27 "Margin" user)
		(31 "F.CrtYd" user "Package Geometry/Place Bound Top")
		(29 "B.CrtYd" user "Package Geometry/Place Bound Bottom")
		(35 "F.Fab" user "Ref Des/Assembly Top")
		(33 "B.Fab" user "Ref Des/Assembly Bottom")
	)
	(footprint ""
		(layer "F.Cu")
		(at 477.9264 -138.7094 90)
		(property "Reference" "R6W30"
			(at 1.01473 0.656336 0)
			(unlocked yes)
			(layer "F.SilkS")
			(effects
				(font
					(size 0.4064 0.254)
					(thickness 0.1524)
				)
			)
		)
		(property "Value" ""
			(at 0 0 90)
			(layer "F.Fab")
			(effects
				(font
					(size 1.27 1.27)
				)
			)
		)
		(duplicate_pad_numbers_are_jumpers no)
		(fp_poly
			(pts
				(xy -0.4953 -0.2032) (xy 0.4953 -0.2032) (xy 0.4953 1.6002) (xy -0.4953 1.6002)
			)
			(stroke
				(width 0)
				(type default)
			)
			(fill no)
			(layer "F.CrtYd")
		)
		(fp_line
			(start 0.4953 -0.2032)
			(end 0.4953 1.6002)
			(stroke
				(width 0.1)
				(type default)
			)
			(layer "F.Fab")
		)
		(fp_line
			(start -0.4953 -0.2032)
			(end 0.4953 -0.2032)
			(stroke
				(width 0.1)
				(type default)
			)
			(layer "F.Fab")
		)
		(fp_line
			(start 0.4953 1.6002)
			(end -0.4953 1.6002)
			(stroke
				(width 0.1)
				(type default)
			)
			(layer "F.Fab")
		)
		(fp_line
			(start -0.4953 1.6002)
			(end -0.4953 -0.2032)
			(stroke
				(width 0.1)
				(type default)
			)
			(layer "F.Fab")
		)
		(pad "1" smd rect
			(at 0 0 90)
			(size 0.762 0.889)
			(layers "F.Cu" "F.Mask" "F.Paste")
			(net "P3V3_STBY")
		)
		(pad "2" smd rect
			(at 0 1.397 90)
			(size 0.762 0.889)
			(layers "F.Cu" "F.Mask" "F.Paste")
			(net "SPA_MID_DBG2_RX_BUF")
		)
		(zone
			(layer "F.Cu")
			(hatch none 0.5)
			(connect_pads
				(clearance 0)
			)
			(min_thickness 0.25)
			(keepout
				(tracks allowed)
				(vias not_allowed)
				(pads allowed)
				(copperpour not_allowed)
				(footprints allowed)
			)
			(placement
				(enabled no)
				(sheetname "")
			)
			(fill
				(thermal_gap 0.5)
				(thermal_bridge_width 0.5)
				(island_removal_mode 0)
			)
			(polygon
				(pts
					(xy 478.8789 -139.0904) (xy 478.3709 -139.0904) (xy 478.3709 -138.3284) (xy 478.8789 -138.3284)
				)
			)
		)
		(zone
			(layer "F.Cu")
			(hatch none 0.5)
			(connect_pads
				(clearance 0)
			)
			(min_thickness 0.25)
			(keepout
				(tracks not_allowed)
				(vias allowed)
				(pads allowed)
				(copperpour not_allowed)
				(footprints allowed)
			)
			(placement
				(enabled no)
				(sheetname "")
			)
			(fill
				(thermal_gap 0.5)
				(thermal_bridge_width 0.5)
				(island_removal_mode 0)
			)
			(polygon
				(pts
					(xy 478.8789 -138.3284) (xy 478.8789 -139.0904) (xy 478.3709 -139.0904) (xy 478.3709 -138.3284)
				)
			)
		)
	)
	(footprint ""
		(layer "F.Cu")
		(at 373.2784 -131.7498 180)
		(property "Reference" "C7B24"
			(at 0 0 180)
			(layer "F.SilkS")
			(hide yes)
			(effects
				(font
					(size 1.27 1.27)
				)
			)
		)
		(property "Value" ""
			(at 0 0 180)
			(layer "F.Fab")
			(effects
				(font
					(size 1.27 1.27)
				)
			)
		)
		(duplicate_pad_numbers_are_jumpers no)
		(fp_rect
			(start -0.4953 1.6002)
			(end 0.4953 -0.2032)
			(stroke
				(width 0)
				(type default)
			)
			(fill no)
			(layer "F.CrtYd")
		)
		(fp_line
			(start 0.4953 1.6002)
			(end -0.4953 1.6002)
			(stroke
				(width 0.1)
				(type default)
			)
			(layer "F.Fab")
		)
		(fp_line
			(start 0.4953 -0.2032)
			(end 0.4953 1.6002)
			(stroke
				(width 0.1)
				(type default)
			)
			(layer "F.Fab")
		)
		(fp_line
			(start -0.4953 1.6002)
			(end -0.4953 -0.2032)
			(stroke
				(width 0.1)
				(type default)
			)
			(layer "F.Fab")
		)
		(fp_line
			(start -0.4953 -0.2032)
			(end 0.4953 -0.2032)
			(stroke
				(width 0.1)
				(type default)
			)
			(layer "F.Fab")
		)
		(pad "1" smd rect
			(at 0 0 180)
			(size 0.762 0.889)
			(layers "F.Cu" "F.Mask" "F.Paste")
			(net "P1V05_PCH_STBY")
		)
		(pad "2" smd rect
			(at 0 1.397 180)
			(size 0.762 0.889)
			(layers "F.Cu" "F.Mask" "F.Paste")
			(net "GND")
		)
		(zone
			(layer "F.Cu")
			(hatch none 0.5)
			(connect_pads
				(clearance 0)
			)
			(min_thickness 0.25)
			(keepout
				(tracks not_allowed)
				(vias allowed)
				(pads allowed)
				(copperpour not_allowed)
				(footprints allowed)
			)
			(placement
				(enabled no)
				(sheetname "")
			)
			(fill
				(thermal_gap 0.5)
				(thermal_bridge_width 0.5)
				(island_removal_mode 0)
			)
			(polygon
				(pts
					(xy 373.6594 -132.7023) (xy 372.8974 -132.7023) (xy 372.8974 -132.1943) (xy 373.6594 -132.1943)
				)
			)
		)
	)
	(footprint ""
		(layer "F.Cu")
		(at 164.973 -65.8114)
		(property "Reference" "C4D44"
			(at 0 0 0)
			(layer "F.SilkS")
			(hide yes)
			(effects
				(font
					(size 1.27 1.27)
				)
			)
		)
		(property "Value" ""
			(at 0 0 0)
			(layer "F.Fab")
			(effects
				(font
					(size 1.27 1.27)
				)
			)
		)
		(duplicate_pad_numbers_are_jumpers no)
		(fp_poly
			(pts
				(xy 0.3048 -0.1016) (xy 0.3048 0.9906) (xy -0.3048 0.9906) (xy -0.3048 -0.1016)
			)
			(stroke
				(width 0)
				(type default)
			)
			(fill no)
			(layer "F.CrtYd")
		)
		(fp_line
			(start -0.3048 -0.1016)
			(end -0.3048 0.9906)
			(stroke
				(width 0.1)
				(type default)
			)
			(layer "F.Fab")
		)
		(fp_line
			(start -0.3048 0.9906)
			(end 0.3048 0.9906)
			(stroke
				(width 0.1)
				(type default)
			)
			(layer "F.Fab")
		)
		(fp_line
			(start 0.3048 -0.1016)
			(end -0.3048 -0.1016)
			(stroke
				(width 0.1)
				(type default)
			)
			(layer "F.Fab")
		)
		(fp_line
			(start 0.3048 0.9906)
			(end 0.3048 -0.1016)
			(stroke
				(width 0.1)
				(type default)
			)
			(layer "F.Fab")
		)
		(pad "1" smd rect
			(at 0 0)
			(size 0.508 0.508)
			(layers "F.Cu" "F.Mask" "F.Paste")
			(net "VR_PVCCIO_CPU1_AVSP")
		)
		(pad "2" smd rect
			(at 0 0.889)
			(size 0.508 0.508)
			(layers "F.Cu" "F.Mask" "F.Paste")
			(net "VSENSE_PVCCIO_CPU1_AVSN")
		)
		(zone
			(layer "F.Cu")
			(hatch none 0.5)
			(connect_pads
				(clearance 0)
			)
			(min_thickness 0.25)
			(keepout
				(tracks allowed)
				(vias not_allowed)
				(pads allowed)
				(copperpour not_allowed)
				(footprints allowed)
			)
			(placement
				(enabled no)
				(sheetname "")
			)
			(fill
				(thermal_gap 0.5)
				(thermal_bridge_width 0.5)
				(island_removal_mode 0)
			)
			(polygon
				(pts
					(xy 164.719 -65.5574) (xy 165.227 -65.5574) (xy 165.227 -65.1764) (xy 164.719 -65.1764)
				)
			)
		)
		(zone
			(layer "F.Cu")
			(hatch none 0.5)
			(connect_pads
				(clearance 0)
			)
			(min_thickness 0.25)
			(keepout
				(tracks not_allowed)
				(vias allowed)
				(pads allowed)
				(copperpour not_allowed)
				(footprints allowed)
			)
			(placement
				(enabled no)
				(sheetname "")
			)
			(fill
				(thermal_gap 0.5)
				(thermal_bridge_width 0.5)
				(island_removal_mode 0)
			)
			(polygon
				(pts
					(xy 164.719 -65.1764) (xy 165.227 -65.1764) (xy 165.227 -65.5574) (xy 164.719 -65.5574)
				)
			)
		)
	)
)
